# SCM (Grand Teton) — schematic netlist excerpt (pin names and nets, part order shuffled) for the footprints in the layout excerpt that follows; sources: Cadence DE-HDL packaged netlist, KiCad conversion of 12092022_DA0F0TMDCD0_F0T_Management_Board_D_brd_V3_OCP.brd

R421  Q_RES  33.2 1% CHIP  pkg 0402LF  page 26 : A = SMB_BMC_MM16_R2_SDA ; B = SMB_BMC_MM16_SDA

U20  NC7SB3157  NC7SB3157P6X IC  pkg SMLF  page 31
  B1  = SPA_SIN_SW_DBG_R
  GND  = GND
  B0  = UART_SYS_DBG_RX_R
  A  = SPA_SIN_SW_BUF_R
  VCC  = P3V3_AUX
  S  = FM_DBG_SW_N

(kicad_pcb
	(version 20260206)
	(generator "pcbnew")
	(generator_version "10.0")
	(general
		(thickness 1.6)
		(legacy_teardrops no)
	)
	(paper "A4")
	(title_block
		(title "12092022_DA0F0TMDCD0_F0T_Management_Board_D_brd_V3_OCP.brd")
		(comment 1 "Grand Teton / footprints 1255-1256 of 1440")
	)
	(layers
		(0 "F.Cu" signal "TOP")
		(4 "In1.Cu" signal "GND")
		(6 "In2.Cu" signal "IN1")
		(8 "In3.Cu" signal "GND1")
		(10 "In4.Cu" signal "IN2")
		(12 "In5.Cu" signal "VCC")
		(14 "In6.Cu" signal "VCC1")
		(16 "In7.Cu" signal "IN3")
		(18 "In8.Cu" signal "GND2")
		(20 "In9.Cu" signal "IN4")
		(22 "In10.Cu" signal "GND3")
		(2 "B.Cu" signal "BOTTOM")
		(9 "F.Adhes" user "F.Adhesive")
		(11 "B.Adhes" user "B.Adhesive")
		(13 "F.Paste" user "Package Geometry/Pastemask Top")
		(15 "B.Paste" user "Package Geometry/Pastemask Bottom")
		(5 "F.SilkS" user "Ref Des/Silkscreen Top")
		(7 "B.SilkS" user "Ref Des/Silkscreen Bottom")
		(1 "F.Mask" user "Board Geometry/Soldermask Top")
		(3 "B.Mask" user "Board Geometry/Soldermask Bottom")
		(17 "Dwgs.User" user "User.Drawings")
		(19 "Cmts.User" user "User.Comments")
		(21 "Eco1.User" user "User.Eco1")
		(23 "Eco2.User" user "User.Eco2")
		(25 "Edge.Cuts" user "Board Geometry/Outline")
		(27 "Margin" user)
		(31 "F.CrtYd" user "Package Geometry/Place Bound Top")
		(29 "B.CrtYd" user "Package Geometry/Place Bound Bottom")
		(35 "F.Fab" user "Ref Des/Assembly Top")
		(33 "B.Fab" user "Ref Des/Assembly Bottom")
	)
	(footprint ""
		(layer "B.Cu")
		(at 68.608448 -26.594562 180)
		(property "Reference" "R421"
			(at 0 0 0)
			(layer "B.SilkS")
			(hide yes)
			(effects
				(font
					(size 1.27 1.27)
				)
				(justify mirror)
			)
		)
		(property "Value" ""
			(at 0 0 0)
			(layer "B.Fab")
			(effects
				(font
					(size 1.27 1.27)
				)
				(justify mirror)
			)
		)
		(duplicate_pad_numbers_are_jumpers no)
		(fp_line
			(start 0.7874 0.4064)
			(end 0.7874 -0.4064)
			(stroke
				(width 0.1524)
				(type default)
			)
			(layer "B.SilkS")
		)
		(fp_line
			(start 0.7874 -0.4064)
			(end -0.7874 -0.4064)
			(stroke
				(width 0.1524)
				(type default)
			)
			(layer "B.SilkS")
		)
		(fp_line
			(start -0.7874 0.4064)
			(end 0.7874 0.4064)
			(stroke
				(width 0.1524)
				(type default)
			)
			(layer "B.SilkS")
		)
		(fp_line
			(start -0.7874 -0.4064)
			(end -0.7874 0.4064)
			(stroke
				(width 0.1524)
				(type default)
			)
			(layer "B.SilkS")
		)
		(fp_line
			(start 0.67945 0.3048)
			(end 0.67945 -0.305054)
			(stroke
				(width 0.1)
				(type default)
			)
			(layer "B.Fab")
		)
		(fp_line
			(start 0.67945 -0.305054)
			(end 0.12065 -0.305054)
			(stroke
				(width 0.1)
				(type default)
			)
			(layer "B.Fab")
		)
		(fp_line
			(start 0.12065 0.3048)
			(end 0.67945 0.3048)
			(stroke
				(width 0.1)
				(type default)
			)
			(layer "B.Fab")
		)
		(fp_line
			(start 0.12065 0.2794)
			(end 0.12065 0.3048)
			(stroke
				(width 0.1)
				(type default)
			)
			(layer "B.Fab")
		)
		(fp_line
			(start 0.12065 -0.2794)
			(end -0.12065 -0.2794)
			(stroke
				(width 0.1)
				(type default)
			)
			(layer "B.Fab")
		)
		(fp_line
			(start 0.12065 -0.305054)
			(end 0.12065 -0.2794)
			(stroke
				(width 0.1)
				(type default)
			)
			(layer "B.Fab")
		)
		(fp_line
			(start -0.120396 0.3048)
			(end -0.120396 0.2794)
			(stroke
				(width 0.1)
				(type default)
			)
			(layer "B.Fab")
		)
		(fp_line
			(start -0.120396 0.2794)
			(end 0.12065 0.2794)
			(stroke
				(width 0.1)
				(type default)
			)
			(layer "B.Fab")
		)
		(fp_line
			(start -0.12065 -0.2794)
			(end -0.12065 -0.3048)
			(stroke
				(width 0.1)
				(type default)
			)
			(layer "B.Fab")
		)
		(fp_line
			(start -0.12065 -0.3048)
			(end -0.67945 -0.3048)
			(stroke
				(width 0.1)
				(type default)
			)
			(layer "B.Fab")
		)
		(fp_line
			(start -0.67945 0.3048)
			(end -0.120396 0.3048)
			(stroke
				(width 0.1)
				(type default)
			)
			(layer "B.Fab")
		)
		(fp_line
			(start -0.67945 -0.3048)
			(end -0.67945 0.3048)
			(stroke
				(width 0.1)
				(type default)
			)
			(layer "B.Fab")
		)
		(pad "1" smd circle
			(at 0.40005 0)
			(size 0 0)
			(layers "B.Cu" "B.Mask" "B.Paste")
			(net "SMB_BMC_MM16_R2_SDA")
		)
		(pad "2" smd circle
			(at -0.40005 0)
			(size 0 0)
			(layers "B.Cu" "B.Mask" "B.Paste")
			(net "SMB_BMC_MM16_SDA")
		)
	)
	(footprint ""
		(layer "B.Cu")
		(at 34.163 -67.437 -90)
		(property "Reference" "U20"
			(at -1.905 -1.87833 270)
			(unlocked yes)
			(layer "B.SilkS")
			(effects
				(font
					(size 0.7874 0.5842)
					(thickness 0.1524)
				)
				(justify mirror)
			)
		)
		(property "Value" ""
			(at 0 0 90)
			(layer "B.Fab")
			(effects
				(font
					(size 1.27 1.27)
				)
				(justify mirror)
			)
		)
		(duplicate_pad_numbers_are_jumpers no)
		(fp_line
			(start -1.7272 1.1176)
			(end 1.7272 1.1176)
			(stroke
				(width 0.1524)
				(type default)
			)
			(layer "B.SilkS")
		)
		(fp_line
			(start 1.7272 1.1176)
			(end 1.7272 -1.1176)
			(stroke
				(width 0.1524)
				(type default)
			)
			(layer "B.SilkS")
		)
		(fp_line
			(start 0 -0.7366)
			(end 0.254 -1.1176)
			(stroke
				(width 0.1524)
				(type default)
			)
			(layer "B.SilkS")
		)
		(fp_line
			(start -1.7272 -1.1176)
			(end -1.7272 1.1176)
			(stroke
				(width 0.1524)
				(type default)
			)
			(layer "B.SilkS")
		)
		(fp_line
			(start -1.7272 -1.1176)
			(end -0.254 -1.1176)
			(stroke
				(width 0.1524)
				(type default)
			)
			(layer "B.SilkS")
		)
		(fp_line
			(start -0.254 -1.1176)
			(end 0 -0.7366)
			(stroke
				(width 0.1524)
				(type default)
			)
			(layer "B.SilkS")
		)
		(fp_line
			(start 0.254 -1.1176)
			(end 1.7272 -1.1176)
			(stroke
				(width 0.1524)
				(type default)
			)
			(layer "B.SilkS")
		)
		(fp_poly
			(pts
				(xy 2.280412 -1.158748) (xy 3.08864 -1.427988) (xy 2.549906 -1.966976)
			)
			(stroke
				(width 0)
				(type default)
			)
			(fill yes)
			(layer "B.SilkS")
		)
		(fp_line
			(start -1.5748 1.1176)
			(end -1.5748 -1.1176)
			(stroke
				(width 0.1)
				(type default)
			)
			(layer "B.Fab")
		)
		(fp_line
			(start 1.5748 1.1176)
			(end -1.5748 1.1176)
			(stroke
				(width 0.1)
				(type default)
			)
			(layer "B.Fab")
		)
		(fp_line
			(start -1.5748 -1.1176)
			(end 1.5748 -1.1176)
			(stroke
				(width 0.1)
				(type default)
			)
			(layer "B.Fab")
		)
		(fp_line
			(start 1.5748 -1.1176)
			(end 1.5748 1.1176)
			(stroke
				(width 0.1)
				(type default)
			)
			(layer "B.Fab")
		)
		(fp_poly
			(pts
				(xy 1.9558 -0.649986) (xy 2.7178 -0.268986) (xy 2.7178 -1.030986)
			)
			(stroke
				(width 0)
				(type default)
			)
			(fill yes)
			(layer "B.Fab")
		)
		(pad "1" smd rect
			(at 0.999998 -0.649986 180)
			(size 0.3556 1.1176)
			(layers "B.Cu" "B.Mask" "B.Paste")
			(net "SPA_SIN_SW_DBG_R")
		)
		(pad "2" smd rect
			(at 0.999998 0 180)
			(size 0.3556 1.1176)
			(layers "B.Cu" "B.Mask" "B.Paste")
			(net "GND")
		)
		(pad "3" smd rect
			(at 0.999998 0.649986 180)
			(size 0.3556 1.1176)
			(layers "B.Cu" "B.Mask" "B.Paste")
			(net "UART_SYS_DBG_RX_R")
		)
		(pad "4" smd rect
			(at -0.999998 0.649986 180)
			(size 0.3556 1.1176)
			(layers "B.Cu" "B.Mask" "B.Paste")
			(net "SPA_SIN_SW_BUF_R")
		)
		(pad "5" smd rect
			(at -0.999998 0 180)
			(size 0.3556 1.1176)
			(layers "B.Cu" "B.Mask" "B.Paste")
			(net "P3V3_AUX")
		)
		(pad "6" smd rect
			(at -0.999998 -0.649986 180)
			(size 0.3556 1.1176)
			(layers "B.Cu" "B.Mask" "B.Paste")
			(net "FM_DBG_SW_N")
		)
	)
)
